(kicad_pcb
	(version 20260206)
	(generator "pcbnew")
	(generator_version "10.0")
	(general
		(thickness 1.6)
		(legacy_teardrops no)
	)
	(paper "A4")
	(title_block
		(title "peb — Lightning_PEB_BRD.brd")
		(comment 1 "Lightning (Wiwynn / Facebook NVMe JBOF) / footprints 1515-1520 of 2563")
	)
	(layers
		(0 "F.Cu" signal "TOP")
		(4 "In1.Cu" signal "L2GND")
		(6 "In2.Cu" signal "L3")
		(8 "In3.Cu" signal "L4VCC")
		(10 "In4.Cu" signal "L5VCC")
		(12 "In5.Cu" signal "L6")
		(14 "In6.Cu" signal "L7GND")
		(2 "B.Cu" signal "BOTTOM")
		(9 "F.Adhes" user "F.Adhesive")
		(11 "B.Adhes" user "B.Adhesive")
		(13 "F.Paste" user "Package Geometry/Pastemask Top")
		(15 "B.Paste" user "Package Geometry/Pastemask Bottom")
		(5 "F.SilkS" user "Ref Des/Silkscreen Top")
		(7 "B.SilkS" user "Ref Des/Silkscreen Bottom")
		(1 "F.Mask" user "Board Geometry/Soldermask Top")
		(3 "B.Mask" user "Board Geometry/Soldermask Bottom")
		(17 "Dwgs.User" user "User.Drawings")
		(19 "Cmts.User" user "User.Comments")
		(21 "Eco1.User" user "User.Eco1")
		(23 "Eco2.User" user "User.Eco2")
		(25 "Edge.Cuts" user "Board Geometry/Outline")
		(27 "Margin" user)
		(31 "F.CrtYd" user "Package Geometry/Place Bound Top")
		(29 "B.CrtYd" user "Package Geometry/Place Bound Bottom")
		(35 "F.Fab" user "Ref Des/Assembly Top")
		(33 "B.Fab" user "Ref Des/Assembly Bottom")
	)
	(footprint ""
		(layer "F.Cu")
		(at 120.5738 -99.8982 90)
		(property "Reference" "R429"
			(at 0 0 90)
			(layer "F.SilkS")
			(hide yes)
			(effects
				(font
					(size 1.27 1.27)
				)
			)
		)
		(property "Value" "2KR2F-3-GP"
			(at 0.064008 -3.993896 90)
			(unlocked yes)
			(layer "F.Fab")
			(hide yes)
			(effects
				(font
					(size 1.016 1.016)
					(thickness 0.1524)
				)
			)
		)
		(property "Device Type" "R402H16"
			(at 0.064008 -5.517896 90)
			(unlocked yes)
			(layer "F.Fab")
			(hide yes)
			(effects
				(font
					(size 1.016 1.016)
					(thickness 0.1524)
				)
			)
		)
		(duplicate_pad_numbers_are_jumpers no)
		(fp_line
			(start 0.508 -0.9398)
			(end -0.508 -0.9398)
			(stroke
				(width 0.1524)
				(type default)
			)
			(layer "F.SilkS")
		)
		(fp_line
			(start -0.508 -0.9398)
			(end -0.508 0.9398)
			(stroke
				(width 0.1524)
				(type default)
			)
			(layer "F.SilkS")
		)
		(fp_rect
			(start -0.508 0.9398)
			(end 0.508 -0.9398)
			(stroke
				(width 0)
				(type default)
			)
			(fill no)
			(layer "F.CrtYd")
		)
		(fp_rect
			(start -0.508 0.9398)
			(end 0.508 -0.9398)
			(stroke
				(width 0)
				(type default)
			)
			(fill no)
			(layer "F.Fab")
		)
		(pad "1" smd custom
			(at 0 -0.4445 90)
			(size 0.1397 0.1397)
			(layers "F.Cu" "F.Mask" "F.Paste")
			(net "P3V3_STBY")
			(options
				(clearance outline)
				(anchor circle)
			)
			(primitives
				(gr_poly
					(pts
						(arc
							(start -0.1778 -0.2794)
							(mid -0.249642 -0.249642)
							(end -0.2794 -0.1778)
						)
						(arc
							(start -0.2794 0.1778)
							(mid -0.249642 0.249642)
							(end -0.1778 0.2794)
						)
						(arc
							(start 0.1778 0.2794)
							(mid 0.249642 0.249642)
							(end 0.2794 0.1778)
						)
						(arc
							(start 0.2794 -0.1778)
							(mid 0.249642 -0.249642)
							(end 0.1778 -0.2794)
						)
					)
					(width 0)
					(fill yes)
				)
			)
		)
		(pad "2" smd custom
			(at 0 0.4445 90)
			(size 0.1397 0.1397)
			(layers "F.Cu" "F.Mask" "F.Paste")
			(net "BUF_I2C_SDA_2_R")
			(options
				(clearance outline)
				(anchor circle)
			)
			(primitives
				(gr_poly
					(pts
						(arc
							(start -0.1778 -0.2794)
							(mid -0.249642 -0.249642)
							(end -0.2794 -0.1778)
						)
						(arc
							(start -0.2794 0.1778)
							(mid -0.249642 0.249642)
							(end -0.1778 0.2794)
						)
						(arc
							(start 0.1778 0.2794)
							(mid 0.249642 0.249642)
							(end 0.2794 0.1778)
						)
						(arc
							(start 0.2794 -0.1778)
							(mid 0.249642 -0.249642)
							(end 0.1778 -0.2794)
						)
					)
					(width 0)
					(fill yes)
				)
			)
		)
	)
	(footprint ""
		(layer "F.Cu")
		(at 69.465952 -148.75891 90)
		(property "Reference" "U16"
			(at 0 0 90)
			(layer "F.SilkS")
			(hide yes)
			(effects
				(font
					(size 1.27 1.27)
				)
			)
		)
		(property "Value" "24LC64-I-SN-GP"
			(at -3.707384 -1.5367 90)
			(unlocked yes)
			(layer "F.Fab")
			(hide yes)
			(effects
				(font
					(size 1.016 1.016)
					(thickness 0.1524)
				)
			)
		)
		(property "Device Type" "SOIC8H69"
			(at -3.707384 -3.0607 90)
			(unlocked yes)
			(layer "F.Fab")
			(hide yes)
			(effects
				(font
					(size 1.016 1.016)
					(thickness 0.1524)
				)
			)
		)
		(duplicate_pad_numbers_are_jumpers no)
		(fp_line
			(start 2.1336 -1.4224)
			(end -2.7432 -1.4224)
			(stroke
				(width 0.1524)
				(type default)
			)
			(layer "F.SilkS")
		)
		(fp_line
			(start -2.7432 -1.4224)
			(end -2.7432 1.4224)
			(stroke
				(width 0.1524)
				(type default)
			)
			(layer "F.SilkS")
		)
		(fp_line
			(start -2.7178 -0.508)
			(end -2.1844 -0.0508)
			(stroke
				(width 0.1524)
				(type default)
			)
			(layer "F.SilkS")
		)
		(fp_line
			(start -2.1844 -0.0508)
			(end -2.7178 0.508)
			(stroke
				(width 0.1524)
				(type default)
			)
			(layer "F.SilkS")
		)
		(fp_line
			(start 2.1336 1.4224)
			(end 2.1336 -1.4224)
			(stroke
				(width 0.1524)
				(type default)
			)
			(layer "F.SilkS")
		)
		(fp_line
			(start -2.7432 1.4224)
			(end 2.1336 1.4224)
			(stroke
				(width 0.1524)
				(type default)
			)
			(layer "F.SilkS")
		)
		(fp_line
			(start -2.7432 1.4224)
			(end -2.6416 1.4224)
			(stroke
				(width 0.1524)
				(type default)
			)
			(layer "F.SilkS")
		)
		(fp_line
			(start -2.6289 3.4417)
			(end -2.6289 1.4732)
			(stroke
				(width 0.381)
				(type default)
			)
			(layer "F.SilkS")
		)
		(fp_poly
			(pts
				(xy -2.2098 -1.4224) (xy -2.2098 1.4224) (xy 2.2098 1.4224) (xy 2.2098 -1.4224)
			)
			(stroke
				(width 0)
				(type default)
			)
			(fill yes)
			(layer "F.SilkS")
		)
		(fp_rect
			(start -2.450084 2.999994)
			(end 2.450084 -2.999994)
			(stroke
				(width 0)
				(type default)
			)
			(fill no)
			(layer "F.CrtYd")
		)
		(fp_poly
			(pts
				(xy -2.8194 3.6322) (xy -2.8194 -3.6322) (xy 2.8194 -3.6322) (xy 2.8194 1.18364) (xy 2.450084 1.18364)
				(xy 2.450084 -2.999994) (xy -2.450084 -2.999994) (xy -2.450084 2.999994) (xy 2.450084 2.999994)
				(xy 2.450084 1.18618) (xy 2.8194 1.18618) (xy 2.8194 3.6322)
			)
			(stroke
				(width 0)
				(type default)
			)
			(fill no)
			(layer "F.CrtYd")
		)
		(fp_rect
			(start -2.8194 3.6322)
			(end 2.8194 -3.6322)
			(stroke
				(width 0)
				(type default)
			)
			(fill no)
			(layer "F.Fab")
		)
		(pad "1" smd rect
			(at -1.905 2.54 90)
			(size 0.635 1.651)
			(layers "F.Cu" "F.Mask" "F.Paste")
			(net "EEPROM_A0_R")
		)
		(pad "2" smd rect
			(at -0.635 2.54 90)
			(size 0.635 1.651)
			(layers "F.Cu" "F.Mask" "F.Paste")
			(net "EEPROM_A1_R")
		)
		(pad "3" smd rect
			(at 0.635 2.54 90)
			(size 0.635 1.651)
			(layers "F.Cu" "F.Mask" "F.Paste")
			(net "EEPROM_A2_R")
		)
		(pad "4" smd rect
			(at 1.905 2.54 90)
			(size 0.635 1.651)
			(layers "F.Cu" "F.Mask" "F.Paste")
			(net "GND")
		)
		(pad "5" smd rect
			(at 1.905 -2.54 90)
			(size 0.635 1.651)
			(layers "F.Cu" "F.Mask" "F.Paste")
			(net "EEPROM_SDA")
		)
		(pad "6" smd rect
			(at 0.635 -2.54 90)
			(size 0.635 1.651)
			(layers "F.Cu" "F.Mask" "F.Paste")
			(net "EEPROM_SCL")
		)
		(pad "7" smd rect
			(at -0.635 -2.54 90)
			(size 0.635 1.651)
			(layers "F.Cu" "F.Mask" "F.Paste")
			(net "EEPROM_WP")
		)
		(pad "8" smd rect
			(at -1.905 -2.54 90)
			(size 0.635 1.651)
			(layers "F.Cu" "F.Mask" "F.Paste")
			(net "P3V3_STBY")
		)
	)
	(footprint ""
		(layer "F.Cu")
		(at 31.9786 -180.5432 90)
		(property "Reference" "C243"
			(at 0 0 90)
			(layer "F.SilkS")
			(hide yes)
			(effects
				(font
					(size 1.27 1.27)
				)
			)
		)
		(property "Value" "SCD1U16V2KX-3GP"
			(at 1.1811 -2.7051 90)
			(unlocked yes)
			(layer "F.Fab")
			(hide yes)
			(effects
				(font
					(size 1.016 1.016)
					(thickness 0.1524)
				)
			)
		)
		(property "Device Type" "C402H22"
			(at 1.1811 -4.2291 90)
			(unlocked yes)
			(layer "F.Fab")
			(hide yes)
			(effects
				(font
					(size 1.016 1.016)
					(thickness 0.1524)
				)
			)
		)
		(duplicate_pad_numbers_are_jumpers no)
		(fp_rect
			(start -0.4318 0.9525)
			(end 0.4318 -0.9525)
			(stroke
				(width 0)
				(type default)
			)
			(fill no)
			(layer "F.CrtYd")
		)
		(fp_rect
			(start -0.4318 0.9525)
			(end 0.4318 -0.9525)
			(stroke
				(width 0)
				(type default)
			)
			(fill no)
			(layer "F.Fab")
		)
		(pad "1" smd custom
			(at 0 -0.4445 90)
			(size 0.1524 0.1524)
			(layers "F.Cu" "F.Mask" "F.Paste")
			(net "P3V3_STBY")
			(options
				(clearance outline)
				(anchor circle)
			)
			(primitives
				(gr_poly
					(pts
						(arc
							(start 0.3048 -0.2032)
							(mid 0.275042 -0.275042)
							(end 0.2032 -0.3048)
						)
						(arc
							(start -0.2032 -0.3048)
							(mid -0.275042 -0.275042)
							(end -0.3048 -0.2032)
						)
						(arc
							(start -0.3048 0.2032)
							(mid -0.275042 0.275042)
							(end -0.2032 0.3048)
						)
						(arc
							(start 0.2032 0.3048)
							(mid 0.275042 0.275042)
							(end 0.3048 0.2032)
						)
					)
					(width 0)
					(fill yes)
				)
			)
		)
		(pad "2" smd custom
			(at 0 0.4445 90)
			(size 0.1524 0.1524)
			(layers "F.Cu" "F.Mask" "F.Paste")
			(net "GND")
			(options
				(clearance outline)
				(anchor circle)
			)
			(primitives
				(gr_poly
					(pts
						(arc
							(start 0.3048 -0.2032)
							(mid 0.275042 -0.275042)
							(end 0.2032 -0.3048)
						)
						(arc
							(start -0.2032 -0.3048)
							(mid -0.275042 -0.275042)
							(end -0.3048 -0.2032)
						)
						(arc
							(start -0.3048 0.2032)
							(mid -0.275042 0.275042)
							(end -0.2032 0.3048)
						)
						(arc
							(start 0.2032 0.3048)
							(mid 0.275042 0.275042)
							(end 0.3048 0.2032)
						)
					)
					(width 0)
					(fill yes)
				)
			)
		)
	)
	(footprint ""
		(layer "F.Cu")
		(at 121.4628 -96.0882 90)
		(property "Reference" "U24"
			(at 0 0 90)
			(layer "F.SilkS")
			(hide yes)
			(effects
				(font
					(size 1.27 1.27)
				)
			)
		)
		(property "Value" "PCA9511ADP-T-GP"
			(at 0 -13.1572 90)
			(unlocked yes)
			(layer "F.Fab")
			(hide yes)
			(effects
				(font
					(size 1.016 1.016)
					(thickness 0.1524)
				)
			)
		)
		(property "Device Type" "SSOIC8-2H44"
			(at 0 -15.1892 90)
			(unlocked yes)
			(layer "F.Fab")
			(hide yes)
			(effects
				(font
					(size 1.016 1.016)
					(thickness 0.1524)
				)
			)
		)
		(duplicate_pad_numbers_are_jumpers no)
		(fp_line
			(start 1.0922 -1.016)
			(end 1.0922 1.016)
			(stroke
				(width 0.1524)
				(type default)
			)
			(layer "F.SilkS")
		)
		(fp_line
			(start -1.9304 -1.016)
			(end 1.0922 -1.016)
			(stroke
				(width 0.1524)
				(type default)
			)
			(layer "F.SilkS")
		)
		(fp_line
			(start -1.524 0)
			(end -1.9304 -0.4064)
			(stroke
				(width 0.1524)
				(type default)
			)
			(layer "F.SilkS")
		)
		(fp_line
			(start -1.524 0)
			(end -1.9304 0.4064)
			(stroke
				(width 0.1524)
				(type default)
			)
			(layer "F.SilkS")
		)
		(fp_line
			(start 1.0922 1.016)
			(end -1.9304 1.016)
			(stroke
				(width 0.1524)
				(type default)
			)
			(layer "F.SilkS")
		)
		(fp_line
			(start -1.9304 1.016)
			(end -1.9304 -1.016)
			(stroke
				(width 0.1524)
				(type default)
			)
			(layer "F.SilkS")
		)
		(fp_line
			(start -1.7018 1.0414)
			(end -1.7018 2.9718)
			(stroke
				(width 0.635)
				(type default)
			)
			(layer "F.SilkS")
		)
		(fp_poly
			(pts
				(xy -1.1938 -1.016) (xy 1.0922 -1.016) (xy 1.0922 1.016) (xy -1.1938 1.016)
			)
			(stroke
				(width 0)
				(type default)
			)
			(fill yes)
			(layer "F.SilkS")
		)
		(fp_rect
			(start -2.0066 3.3401)
			(end 2.0066 -3.3401)
			(stroke
				(width 0)
				(type default)
			)
			(fill no)
			(layer "F.CrtYd")
		)
		(fp_poly
			(pts
				(xy -2.0066 -3.3401) (xy 2.0066 -3.3401) (xy 2.0066 3.3401) (xy -2.0066 3.3401)
			)
			(stroke
				(width 0)
				(type default)
			)
			(fill no)
			(layer "F.Fab")
		)
		(pad "1" smd rect
			(at -0.97536 2.0701 90)
			(size 0.4064 1.524)
			(layers "F.Cu" "F.Mask" "F.Paste")
			(net "I2C10_BUFF_EN")
		)
		(pad "2" smd rect
			(at -0.32512 2.0701 90)
			(size 0.4064 1.524)
			(layers "F.Cu" "F.Mask" "F.Paste")
			(net "BMC_I2C10_8536_SCL_R")
		)
		(pad "3" smd rect
			(at 0.32512 2.0701 90)
			(size 0.4064 1.524)
			(layers "F.Cu" "F.Mask" "F.Paste")
			(net "BUF_I2C_SCL_2_R")
		)
		(pad "4" smd rect
			(at 0.97536 2.0701 90)
			(size 0.4064 1.524)
			(layers "F.Cu" "F.Mask" "F.Paste")
			(net "GND")
		)
		(pad "5" smd rect
			(at 0.97536 -2.0701 90)
			(size 0.4064 1.524)
			(layers "F.Cu" "F.Mask" "F.Paste")
			(net "I2C10_BUF_READY")
		)
		(pad "6" smd rect
			(at 0.32512 -2.0701 90)
			(size 0.4064 1.524)
			(layers "F.Cu" "F.Mask" "F.Paste")
			(net "BUF_I2C_SDA_2_R")
		)
		(pad "7" smd rect
			(at -0.32512 -2.0701 90)
			(size 0.4064 1.524)
			(layers "F.Cu" "F.Mask" "F.Paste")
			(net "BMC_I2C10_8536_SDA_R")
		)
		(pad "8" smd rect
			(at -0.97536 -2.0701 90)
			(size 0.4064 1.524)
			(layers "F.Cu" "F.Mask" "F.Paste")
			(net "P3V3_STBY")
		)
	)
	(footprint ""
		(layer "F.Cu")
		(at 184.10428 -4.25196)
		(property "Reference" "R2954"
			(at 0 0 0)
			(layer "F.SilkS")
			(hide yes)
			(effects
				(font
					(size 1.27 1.27)
				)
			)
		)
		(property "Value" "0R2J-2-GP"
			(at 0.064008 -3.993896 0)
			(unlocked yes)
			(layer "F.Fab")
			(hide yes)
			(effects
				(font
					(size 1.016 1.016)
					(thickness 0.1524)
				)
			)
		)
		(property "Device Type" "R402H16"
			(at 0.064008 -5.517896 0)
			(unlocked yes)
			(layer "F.Fab")
			(hide yes)
			(effects
				(font
					(size 1.016 1.016)
					(thickness 0.1524)
				)
			)
		)
		(duplicate_pad_numbers_are_jumpers no)
		(fp_line
			(start -0.508 -0.9398)
			(end -0.508 0.9398)
			(stroke
				(width 0.1524)
				(type default)
			)
			(layer "F.SilkS")
		)
		(fp_line
			(start 0.508 -0.9398)
			(end -0.508 -0.9398)
			(stroke
				(width 0.1524)
				(type default)
			)
			(layer "F.SilkS")
		)
		(fp_rect
			(start -0.508 0.9398)
			(end 0.508 -0.9398)
			(stroke
				(width 0)
				(type default)
			)
			(fill no)
			(layer "F.CrtYd")
		)
		(fp_rect
			(start -0.508 0.9398)
			(end 0.508 -0.9398)
			(stroke
				(width 0)
				(type default)
			)
			(fill no)
			(layer "F.Fab")
		)
		(pad "1" smd custom
			(at 0 -0.4445)
			(size 0.1397 0.1397)
			(layers "F.Cu" "F.Mask" "F.Paste")
			(net "HOST2_RST_N")
			(options
				(clearance outline)
				(anchor circle)
			)
			(primitives
				(gr_poly
					(pts
						(arc
							(start -0.1778 -0.2794)
							(mid -0.249642 -0.249642)
							(end -0.2794 -0.1778)
						)
						(arc
							(start -0.2794 0.1778)
							(mid -0.249642 0.249642)
							(end -0.1778 0.2794)
						)
						(arc
							(start 0.1778 0.2794)
							(mid 0.249642 0.249642)
							(end 0.2794 0.1778)
						)
						(arc
							(start 0.2794 -0.1778)
							(mid 0.249642 -0.249642)
							(end 0.1778 -0.2794)
						)
					)
					(width 0)
					(fill yes)
				)
			)
		)
		(pad "2" smd custom
			(at 0 0.4445)
			(size 0.1397 0.1397)
			(layers "F.Cu" "F.Mask" "F.Paste")
			(net "HOST2_RST_N_C")
			(options
				(clearance outline)
				(anchor circle)
			)
			(primitives
				(gr_poly
					(pts
						(arc
							(start -0.1778 -0.2794)
							(mid -0.249642 -0.249642)
							(end -0.2794 -0.1778)
						)
						(arc
							(start -0.2794 0.1778)
							(mid -0.249642 0.249642)
							(end -0.1778 0.2794)
						)
						(arc
							(start 0.1778 0.2794)
							(mid 0.249642 0.249642)
							(end 0.2794 0.1778)
						)
						(arc
							(start 0.2794 -0.1778)
							(mid 0.249642 -0.249642)
							(end 0.1778 -0.2794)
						)
					)
					(width 0)
					(fill yes)
				)
			)
		)
	)
	(footprint ""
		(layer "F.Cu")
		(at 118.23319 -48.43272 90)
		(property "Reference" "JP6"
			(at 0 0 90)
			(layer "F.SilkS")
			(hide yes)
			(effects
				(font
					(size 1.27 1.27)
				)
			)
		)
		(property "Value" "PIN-CON3-S-GP"
			(at -5.588 -5.3086 90)
			(unlocked yes)
			(layer "F.Fab")
			(hide yes)
			(effects
				(font
					(size 1.016 1.016)
					(thickness 0.1524)
				)
			)
		)
		(property "Device Type" "21S-91-03GB01"
			(at -5.588 -6.8326 90)
			(unlocked yes)
			(layer "F.Fab")
			(hide yes)
			(effects
				(font
					(size 1.016 1.016)
					(thickness 0.1524)
				)
			)
		)
		(duplicate_pad_numbers_are_jumpers no)
		(fp_line
			(start -4.0132 -1.6256)
			(end -2.7432 -1.6256)
			(stroke
				(width 0.4064)
				(type default)
			)
			(layer "F.SilkS")
		)
		(fp_line
			(start 3.8862 -1.4986)
			(end -3.8862 -1.4986)
			(stroke
				(width 0.1524)
				(type default)
			)
			(layer "F.SilkS")
		)
		(fp_line
			(start -3.8862 -1.4986)
			(end -3.8862 1.4986)
			(stroke
				(width 0.1524)
				(type default)
			)
			(layer "F.SilkS")
		)
		(fp_line
			(start -4.0132 -0.3556)
			(end -4.0132 -1.6256)
			(stroke
				(width 0.4064)
				(type default)
			)
			(layer "F.SilkS")
		)
		(fp_line
			(start 3.8862 1.4986)
			(end 3.8862 -1.4986)
			(stroke
				(width 0.1524)
				(type default)
			)
			(layer "F.SilkS")
		)
		(fp_line
			(start -3.8862 1.4986)
			(end 3.8862 1.4986)
			(stroke
				(width 0.1524)
				(type default)
			)
			(layer "F.SilkS")
		)
		(fp_circle
			(center 2.54 0)
			(end 2.54 1.0668)
			(stroke
				(width 0.3048)
				(type default)
			)
			(fill no)
			(layer "F.SilkS")
		)
		(fp_circle
			(center 0 0)
			(end 0 1.0668)
			(stroke
				(width 0.3048)
				(type default)
			)
			(fill no)
			(layer "F.SilkS")
		)
		(fp_circle
			(center -2.54 0)
			(end -2.54 1.0668)
			(stroke
				(width 0.3048)
				(type default)
			)
			(fill no)
			(layer "F.SilkS")
		)
		(fp_rect
			(start -3.6322 1.2446)
			(end 3.6322 -1.2446)
			(stroke
				(width 0)
				(type default)
			)
			(fill no)
			(layer "F.CrtYd")
		)
		(fp_poly
			(pts
				(xy 4.1402 -1.2446) (xy -3.6322 -1.2446) (xy -3.6322 1.2446) (xy 3.6322 1.2446) (xy 3.6322 -1.2319)
				(xy 4.1402 -1.2319) (xy 4.1402 1.7526) (xy -4.1402 1.7526) (xy -4.1402 -1.7526) (xy 4.1402 -1.7526)
			)
			(stroke
				(width 0)
				(type default)
			)
			(fill no)
			(layer "F.CrtYd")
		)
		(fp_rect
			(start -4.1402 1.7526)
			(end 4.1402 -1.7526)
			(stroke
				(width 0)
				(type default)
			)
			(fill no)
			(layer "F.Fab")
		)
		(pad "1" thru_hole circle
			(at -2.54 0 90)
			(size 1.4224 1.4224)
			(drill 1.016)
			(layers "*.Cu" "*.Mask")
			(remove_unused_layers no)
			(net "BMC_ADD2_PWR")
			(clearance 0.1524)
			(thermal_gap 0.1524)
		)
		(pad "2" thru_hole circle
			(at 0 0 90)
			(size 1.4224 1.4224)
			(drill 1.016)
			(layers "*.Cu" "*.Mask")
			(remove_unused_layers no)
			(net "BMC_ADD2")
			(clearance 0.1524)
			(thermal_gap 0.1524)
		)
		(pad "3" thru_hole circle
			(at 2.54 0 90)
			(size 1.4224 1.4224)
			(drill 1.016)
			(layers "*.Cu" "*.Mask")
			(remove_unused_layers no)
			(net "BMC_ADD2_GND")
			(clearance 0.1524)
			(thermal_gap 0.1524)
		)
	)
)
